(kicad_pcb
	(version 20260206)
	(generator "pcbnew")
	(generator_version "10.0")
	(general
		(thickness 1.6)
		(legacy_teardrops no)
	)
	(paper "A4")
	(title_block
		(title "04192023_DAF0TMB3IC0_F0TG_MB_C_brd_V02_OCP.brd")
		(comment 1 "Grand Teton / footprints 4093-4099 of 8354")
	)
	(layers
		(0 "F.Cu" signal "TOP")
		(4 "In1.Cu" signal "GND")
		(6 "In2.Cu" signal "IN1")
		(8 "In3.Cu" signal "GND1")
		(10 "In4.Cu" signal "IN2")
		(12 "In5.Cu" signal "GND2")
		(14 "In6.Cu" signal "IN3")
		(16 "In7.Cu" signal "GND3")
		(18 "In8.Cu" signal "VCC")
		(20 "In9.Cu" signal "VCC1")
		(22 "In10.Cu" signal "GND4")
		(24 "In11.Cu" signal "IN4")
		(26 "In12.Cu" signal "GND5")
		(28 "In13.Cu" signal "IN5")
		(30 "In14.Cu" signal "GND6")
		(32 "In15.Cu" signal "IN6")
		(34 "In16.Cu" signal "GND7")
		(2 "B.Cu" signal "BOTTOM")
		(9 "F.Adhes" user "F.Adhesive")
		(11 "B.Adhes" user "B.Adhesive")
		(13 "F.Paste" user "Package Geometry/Pastemask Top")
		(15 "B.Paste" user "Package Geometry/Pastemask Bottom")
		(5 "F.SilkS" user "Ref Des/Silkscreen Top")
		(7 "B.SilkS" user "Ref Des/Silkscreen Bottom")
		(1 "F.Mask" user "Board Geometry/Soldermask Top")
		(3 "B.Mask" user "Board Geometry/Soldermask Bottom")
		(17 "Dwgs.User" user "User.Drawings")
		(19 "Cmts.User" user "User.Comments")
		(21 "Eco1.User" user "User.Eco1")
		(23 "Eco2.User" user "User.Eco2")
		(25 "Edge.Cuts" user "Board Geometry/Outline")
		(27 "Margin" user)
		(31 "F.CrtYd" user "Package Geometry/Place Bound Top")
		(29 "B.CrtYd" user "Package Geometry/Place Bound Bottom")
		(35 "F.Fab" user "Ref Des/Assembly Top")
		(33 "B.Fab" user "Ref Des/Assembly Bottom")
	)
	(footprint ""
		(layer "F.Cu")
		(at 414.316418 -366.780064)
		(property "Reference" "R122"
			(at 0 0 0)
			(layer "F.SilkS")
			(hide yes)
			(effects
				(font
					(size 1.27 1.27)
				)
			)
		)
		(property "Value" ""
			(at 0 0 0)
			(layer "F.Fab")
			(effects
				(font
					(size 1.27 1.27)
				)
			)
		)
		(duplicate_pad_numbers_are_jumpers no)
		(fp_line
			(start -0.7874 -0.4064)
			(end 0.7874 -0.4064)
			(stroke
				(width 0.1524)
				(type default)
			)
			(layer "F.SilkS")
		)
		(fp_line
			(start -0.7874 0.4064)
			(end -0.7874 -0.4064)
			(stroke
				(width 0.1524)
				(type default)
			)
			(layer "F.SilkS")
		)
		(fp_line
			(start 0.7874 -0.4064)
			(end 0.7874 0.4064)
			(stroke
				(width 0.1524)
				(type default)
			)
			(layer "F.SilkS")
		)
		(fp_line
			(start 0.7874 0.4064)
			(end -0.7874 0.4064)
			(stroke
				(width 0.1524)
				(type default)
			)
			(layer "F.SilkS")
		)
		(fp_line
			(start -0.67945 -0.305054)
			(end -0.12065 -0.305054)
			(stroke
				(width 0.1)
				(type default)
			)
			(layer "F.Fab")
		)
		(fp_line
			(start -0.67945 0.3048)
			(end -0.67945 -0.305054)
			(stroke
				(width 0.1)
				(type default)
			)
			(layer "F.Fab")
		)
		(fp_line
			(start -0.12065 -0.305054)
			(end -0.12065 -0.2794)
			(stroke
				(width 0.1)
				(type default)
			)
			(layer "F.Fab")
		)
		(fp_line
			(start -0.12065 -0.2794)
			(end 0.12065 -0.2794)
			(stroke
				(width 0.1)
				(type default)
			)
			(layer "F.Fab")
		)
		(fp_line
			(start -0.12065 0.2794)
			(end -0.12065 0.3048)
			(stroke
				(width 0.1)
				(type default)
			)
			(layer "F.Fab")
		)
		(fp_line
			(start -0.12065 0.3048)
			(end -0.67945 0.3048)
			(stroke
				(width 0.1)
				(type default)
			)
			(layer "F.Fab")
		)
		(fp_line
			(start 0.120396 0.2794)
			(end -0.12065 0.2794)
			(stroke
				(width 0.1)
				(type default)
			)
			(layer "F.Fab")
		)
		(fp_line
			(start 0.120396 0.3048)
			(end 0.120396 0.2794)
			(stroke
				(width 0.1)
				(type default)
			)
			(layer "F.Fab")
		)
		(fp_line
			(start 0.12065 -0.3048)
			(end 0.67945 -0.3048)
			(stroke
				(width 0.1)
				(type default)
			)
			(layer "F.Fab")
		)
		(fp_line
			(start 0.12065 -0.2794)
			(end 0.12065 -0.3048)
			(stroke
				(width 0.1)
				(type default)
			)
			(layer "F.Fab")
		)
		(fp_line
			(start 0.67945 -0.3048)
			(end 0.67945 0.3048)
			(stroke
				(width 0.1)
				(type default)
			)
			(layer "F.Fab")
		)
		(fp_line
			(start 0.67945 0.3048)
			(end 0.120396 0.3048)
			(stroke
				(width 0.1)
				(type default)
			)
			(layer "F.Fab")
		)
		(pad "1" smd circle
			(at -0.40005 0)
			(size 0 0)
			(layers "F.Cu" "F.Mask" "F.Paste")
			(net "PWRGD_PVDD11_S3_P0")
		)
		(pad "2" smd circle
			(at 0.40005 0)
			(size 0 0)
			(layers "F.Cu" "F.Mask" "F.Paste")
			(net "PWRGD_PVDD11_S3_P0_R")
		)
	)
	(footprint ""
		(layer "F.Cu")
		(at 63.999364 -408.517344 -90)
		(property "Reference" "C6639"
			(at 0 0 270)
			(layer "F.SilkS")
			(hide yes)
			(effects
				(font
					(size 1.27 1.27)
				)
			)
		)
		(property "Value" ""
			(at 0 0 270)
			(layer "F.Fab")
			(effects
				(font
					(size 1.27 1.27)
				)
			)
		)
		(duplicate_pad_numbers_are_jumpers no)
		(fp_line
			(start -0.299974 0.150114)
			(end -0.299974 -0.150114)
			(stroke
				(width 0.1)
				(type default)
			)
			(layer "F.Fab")
		)
		(fp_line
			(start 0.299974 0.150114)
			(end -0.299974 0.150114)
			(stroke
				(width 0.1)
				(type default)
			)
			(layer "F.Fab")
		)
		(fp_line
			(start -0.299974 -0.150114)
			(end 0.299974 -0.150114)
			(stroke
				(width 0.1)
				(type default)
			)
			(layer "F.Fab")
		)
		(fp_line
			(start 0.299974 -0.150114)
			(end 0.299974 0.150114)
			(stroke
				(width 0.1)
				(type default)
			)
			(layer "F.Fab")
		)
		(pad "1" smd rect
			(at -0.2667 0 270)
			(size 0.3048 0.381)
			(layers "F.Cu" "F.Mask" "F.Paste")
			(net "P5E_CPU1_P0_TX_BUF_C_DP<5>")
		)
		(pad "2" smd rect
			(at 0.2667 0 270)
			(size 0.3048 0.381)
			(layers "F.Cu" "F.Mask" "F.Paste")
			(net "P5E_CPU1_P0_TX_BUF_DP<5>")
		)
	)
	(footprint ""
		(layer "F.Cu")
		(at 439.029602 -425.94911 180)
		(property "Reference" "R6786"
			(at 0 0 180)
			(layer "F.SilkS")
			(hide yes)
			(effects
				(font
					(size 1.27 1.27)
				)
			)
		)
		(property "Value" ""
			(at 0 0 180)
			(layer "F.Fab")
			(effects
				(font
					(size 1.27 1.27)
				)
			)
		)
		(duplicate_pad_numbers_are_jumpers no)
		(fp_line
			(start 0.7874 0.4064)
			(end -0.7874 0.4064)
			(stroke
				(width 0.1524)
				(type default)
			)
			(layer "F.SilkS")
		)
		(fp_line
			(start 0.7874 -0.4064)
			(end 0.7874 0.4064)
			(stroke
				(width 0.1524)
				(type default)
			)
			(layer "F.SilkS")
		)
		(fp_line
			(start -0.7874 0.4064)
			(end -0.7874 -0.4064)
			(stroke
				(width 0.1524)
				(type default)
			)
			(layer "F.SilkS")
		)
		(fp_line
			(start -0.7874 -0.4064)
			(end 0.7874 -0.4064)
			(stroke
				(width 0.1524)
				(type default)
			)
			(layer "F.SilkS")
		)
		(fp_line
			(start 0.67945 0.3048)
			(end 0.120396 0.3048)
			(stroke
				(width 0.1)
				(type default)
			)
			(layer "F.Fab")
		)
		(fp_line
			(start 0.67945 -0.3048)
			(end 0.67945 0.3048)
			(stroke
				(width 0.1)
				(type default)
			)
			(layer "F.Fab")
		)
		(fp_line
			(start 0.12065 -0.2794)
			(end 0.12065 -0.3048)
			(stroke
				(width 0.1)
				(type default)
			)
			(layer "F.Fab")
		)
		(fp_line
			(start 0.12065 -0.3048)
			(end 0.67945 -0.3048)
			(stroke
				(width 0.1)
				(type default)
			)
			(layer "F.Fab")
		)
		(fp_line
			(start 0.120396 0.3048)
			(end 0.120396 0.2794)
			(stroke
				(width 0.1)
				(type default)
			)
			(layer "F.Fab")
		)
		(fp_line
			(start 0.120396 0.2794)
			(end -0.12065 0.2794)
			(stroke
				(width 0.1)
				(type default)
			)
			(layer "F.Fab")
		)
		(fp_line
			(start -0.12065 0.3048)
			(end -0.67945 0.3048)
			(stroke
				(width 0.1)
				(type default)
			)
			(layer "F.Fab")
		)
		(fp_line
			(start -0.12065 0.2794)
			(end -0.12065 0.3048)
			(stroke
				(width 0.1)
				(type default)
			)
			(layer "F.Fab")
		)
		(fp_line
			(start -0.12065 -0.2794)
			(end 0.12065 -0.2794)
			(stroke
				(width 0.1)
				(type default)
			)
			(layer "F.Fab")
		)
		(fp_line
			(start -0.12065 -0.305054)
			(end -0.12065 -0.2794)
			(stroke
				(width 0.1)
				(type default)
			)
			(layer "F.Fab")
		)
		(fp_line
			(start -0.67945 0.3048)
			(end -0.67945 -0.305054)
			(stroke
				(width 0.1)
				(type default)
			)
			(layer "F.Fab")
		)
		(fp_line
			(start -0.67945 -0.305054)
			(end -0.12065 -0.305054)
			(stroke
				(width 0.1)
				(type default)
			)
			(layer "F.Fab")
		)
		(pad "1" smd circle
			(at -0.40005 0 180)
			(size 0 0)
			(layers "F.Cu" "F.Mask" "F.Paste")
			(net "P0V9_RETIMER_CPU0_EN0_R")
		)
		(pad "2" smd circle
			(at 0.40005 0 180)
			(size 0 0)
			(layers "F.Cu" "F.Mask" "F.Paste")
			(net "GND")
		)
	)
	(footprint ""
		(layer "F.Cu")
		(at 11.665458 -422.551098 180)
		(property "Reference" "R6174"
			(at 0 0 180)
			(layer "F.SilkS")
			(hide yes)
			(effects
				(font
					(size 1.27 1.27)
				)
			)
		)
		(property "Value" ""
			(at 0 0 180)
			(layer "F.Fab")
			(effects
				(font
					(size 1.27 1.27)
				)
			)
		)
		(duplicate_pad_numbers_are_jumpers no)
		(fp_line
			(start 0.7874 0.4064)
			(end -0.7874 0.4064)
			(stroke
				(width 0.1524)
				(type default)
			)
			(layer "F.SilkS")
		)
		(fp_line
			(start 0.7874 -0.4064)
			(end 0.7874 0.4064)
			(stroke
				(width 0.1524)
				(type default)
			)
			(layer "F.SilkS")
		)
		(fp_line
			(start -0.7874 0.4064)
			(end -0.7874 -0.4064)
			(stroke
				(width 0.1524)
				(type default)
			)
			(layer "F.SilkS")
		)
		(fp_line
			(start -0.7874 -0.4064)
			(end 0.7874 -0.4064)
			(stroke
				(width 0.1524)
				(type default)
			)
			(layer "F.SilkS")
		)
		(fp_line
			(start 0.67945 0.3048)
			(end 0.120396 0.3048)
			(stroke
				(width 0.1)
				(type default)
			)
			(layer "F.Fab")
		)
		(fp_line
			(start 0.67945 -0.3048)
			(end 0.67945 0.3048)
			(stroke
				(width 0.1)
				(type default)
			)
			(layer "F.Fab")
		)
		(fp_line
			(start 0.12065 -0.2794)
			(end 0.12065 -0.3048)
			(stroke
				(width 0.1)
				(type default)
			)
			(layer "F.Fab")
		)
		(fp_line
			(start 0.12065 -0.3048)
			(end 0.67945 -0.3048)
			(stroke
				(width 0.1)
				(type default)
			)
			(layer "F.Fab")
		)
		(fp_line
			(start 0.120396 0.3048)
			(end 0.120396 0.2794)
			(stroke
				(width 0.1)
				(type default)
			)
			(layer "F.Fab")
		)
		(fp_line
			(start 0.120396 0.2794)
			(end -0.12065 0.2794)
			(stroke
				(width 0.1)
				(type default)
			)
			(layer "F.Fab")
		)
		(fp_line
			(start -0.12065 0.3048)
			(end -0.67945 0.3048)
			(stroke
				(width 0.1)
				(type default)
			)
			(layer "F.Fab")
		)
		(fp_line
			(start -0.12065 0.2794)
			(end -0.12065 0.3048)
			(stroke
				(width 0.1)
				(type default)
			)
			(layer "F.Fab")
		)
		(fp_line
			(start -0.12065 -0.2794)
			(end 0.12065 -0.2794)
			(stroke
				(width 0.1)
				(type default)
			)
			(layer "F.Fab")
		)
		(fp_line
			(start -0.12065 -0.305054)
			(end -0.12065 -0.2794)
			(stroke
				(width 0.1)
				(type default)
			)
			(layer "F.Fab")
		)
		(fp_line
			(start -0.67945 0.3048)
			(end -0.67945 -0.305054)
			(stroke
				(width 0.1)
				(type default)
			)
			(layer "F.Fab")
		)
		(fp_line
			(start -0.67945 -0.305054)
			(end -0.12065 -0.305054)
			(stroke
				(width 0.1)
				(type default)
			)
			(layer "F.Fab")
		)
		(pad "1" smd circle
			(at -0.40005 0 180)
			(size 0 0)
			(layers "F.Cu" "F.Mask" "F.Paste")
			(net "FM_P2E_BUF2_EQA0")
		)
		(pad "2" smd circle
			(at 0.40005 0 180)
			(size 0 0)
			(layers "F.Cu" "F.Mask" "F.Paste")
			(net "GND")
		)
	)
	(footprint ""
		(layer "F.Cu")
		(at 193.929 -100.294948 -90)
		(property "Reference" "R223"
			(at 0 0 270)
			(layer "F.SilkS")
			(hide yes)
			(effects
				(font
					(size 1.27 1.27)
				)
			)
		)
		(property "Value" ""
			(at 0 0 270)
			(layer "F.Fab")
			(effects
				(font
					(size 1.27 1.27)
				)
			)
		)
		(duplicate_pad_numbers_are_jumpers no)
		(fp_line
			(start -0.7874 0.4064)
			(end -0.7874 -0.4064)
			(stroke
				(width 0.1524)
				(type default)
			)
			(layer "F.SilkS")
		)
		(fp_line
			(start 0.7874 0.4064)
			(end -0.7874 0.4064)
			(stroke
				(width 0.1524)
				(type default)
			)
			(layer "F.SilkS")
		)
		(fp_line
			(start -0.7874 -0.4064)
			(end 0.7874 -0.4064)
			(stroke
				(width 0.1524)
				(type default)
			)
			(layer "F.SilkS")
		)
		(fp_line
			(start 0.7874 -0.4064)
			(end 0.7874 0.4064)
			(stroke
				(width 0.1524)
				(type default)
			)
			(layer "F.SilkS")
		)
		(fp_line
			(start -0.67945 0.3048)
			(end -0.67945 -0.305054)
			(stroke
				(width 0.1)
				(type default)
			)
			(layer "F.Fab")
		)
		(fp_line
			(start -0.12065 0.3048)
			(end -0.67945 0.3048)
			(stroke
				(width 0.1)
				(type default)
			)
			(layer "F.Fab")
		)
		(fp_line
			(start 0.120396 0.3048)
			(end 0.120396 0.2794)
			(stroke
				(width 0.1)
				(type default)
			)
			(layer "F.Fab")
		)
		(fp_line
			(start 0.67945 0.3048)
			(end 0.120396 0.3048)
			(stroke
				(width 0.1)
				(type default)
			)
			(layer "F.Fab")
		)
		(fp_line
			(start -0.12065 0.2794)
			(end -0.12065 0.3048)
			(stroke
				(width 0.1)
				(type default)
			)
			(layer "F.Fab")
		)
		(fp_line
			(start 0.120396 0.2794)
			(end -0.12065 0.2794)
			(stroke
				(width 0.1)
				(type default)
			)
			(layer "F.Fab")
		)
		(fp_line
			(start -0.12065 -0.2794)
			(end 0.12065 -0.2794)
			(stroke
				(width 0.1)
				(type default)
			)
			(layer "F.Fab")
		)
		(fp_line
			(start 0.12065 -0.2794)
			(end 0.12065 -0.3048)
			(stroke
				(width 0.1)
				(type default)
			)
			(layer "F.Fab")
		)
		(fp_line
			(start 0.12065 -0.3048)
			(end 0.67945 -0.3048)
			(stroke
				(width 0.1)
				(type default)
			)
			(layer "F.Fab")
		)
		(fp_line
			(start 0.67945 -0.3048)
			(end 0.67945 0.3048)
			(stroke
				(width 0.1)
				(type default)
			)
			(layer "F.Fab")
		)
		(fp_line
			(start -0.67945 -0.305054)
			(end -0.12065 -0.305054)
			(stroke
				(width 0.1)
				(type default)
			)
			(layer "F.Fab")
		)
		(fp_line
			(start -0.12065 -0.305054)
			(end -0.12065 -0.2794)
			(stroke
				(width 0.1)
				(type default)
			)
			(layer "F.Fab")
		)
		(pad "1" smd circle
			(at -0.40005 0 270)
			(size 0 0)
			(layers "F.Cu" "F.Mask" "F.Paste")
			(net "FM_CPU0_SP5R4")
		)
		(pad "2" smd circle
			(at 0.40005 0 270)
			(size 0 0)
			(layers "F.Cu" "F.Mask" "F.Paste")
			(net "CPU0_SP5R4")
		)
	)
	(footprint ""
		(layer "F.Cu")
		(at 368.130836 -323.466968 90)
		(property "Reference" "R1204"
			(at 0 0 90)
			(layer "F.SilkS")
			(hide yes)
			(effects
				(font
					(size 1.27 1.27)
				)
			)
		)
		(property "Value" ""
			(at 0 0 90)
			(layer "F.Fab")
			(effects
				(font
					(size 1.27 1.27)
				)
			)
		)
		(duplicate_pad_numbers_are_jumpers no)
		(fp_line
			(start 0.7874 -0.4064)
			(end 0.7874 0.4064)
			(stroke
				(width 0.1524)
				(type default)
			)
			(layer "F.SilkS")
		)
		(fp_line
			(start -0.7874 -0.4064)
			(end 0.7874 -0.4064)
			(stroke
				(width 0.1524)
				(type default)
			)
			(layer "F.SilkS")
		)
		(fp_line
			(start 0.7874 0.4064)
			(end -0.7874 0.4064)
			(stroke
				(width 0.1524)
				(type default)
			)
			(layer "F.SilkS")
		)
		(fp_line
			(start -0.7874 0.4064)
			(end -0.7874 -0.4064)
			(stroke
				(width 0.1524)
				(type default)
			)
			(layer "F.SilkS")
		)
		(fp_line
			(start -0.12065 -0.305054)
			(end -0.12065 -0.2794)
			(stroke
				(width 0.1)
				(type default)
			)
			(layer "F.Fab")
		)
		(fp_line
			(start -0.67945 -0.305054)
			(end -0.12065 -0.305054)
			(stroke
				(width 0.1)
				(type default)
			)
			(layer "F.Fab")
		)
		(fp_line
			(start 0.67945 -0.3048)
			(end 0.67945 0.3048)
			(stroke
				(width 0.1)
				(type default)
			)
			(layer "F.Fab")
		)
		(fp_line
			(start 0.12065 -0.3048)
			(end 0.67945 -0.3048)
			(stroke
				(width 0.1)
				(type default)
			)
			(layer "F.Fab")
		)
		(fp_line
			(start 0.12065 -0.2794)
			(end 0.12065 -0.3048)
			(stroke
				(width 0.1)
				(type default)
			)
			(layer "F.Fab")
		)
		(fp_line
			(start -0.12065 -0.2794)
			(end 0.12065 -0.2794)
			(stroke
				(width 0.1)
				(type default)
			)
			(layer "F.Fab")
		)
		(fp_line
			(start 0.120396 0.2794)
			(end -0.12065 0.2794)
			(stroke
				(width 0.1)
				(type default)
			)
			(layer "F.Fab")
		)
		(fp_line
			(start -0.12065 0.2794)
			(end -0.12065 0.3048)
			(stroke
				(width 0.1)
				(type default)
			)
			(layer "F.Fab")
		)
		(fp_line
			(start 0.67945 0.3048)
			(end 0.120396 0.3048)
			(stroke
				(width 0.1)
				(type default)
			)
			(layer "F.Fab")
		)
		(fp_line
			(start 0.120396 0.3048)
			(end 0.120396 0.2794)
			(stroke
				(width 0.1)
				(type default)
			)
			(layer "F.Fab")
		)
		(fp_line
			(start -0.12065 0.3048)
			(end -0.67945 0.3048)
			(stroke
				(width 0.1)
				(type default)
			)
			(layer "F.Fab")
		)
		(fp_line
			(start -0.67945 0.3048)
			(end -0.67945 -0.305054)
			(stroke
				(width 0.1)
				(type default)
			)
			(layer "F.Fab")
		)
		(pad "1" smd circle
			(at -0.40005 0 90)
			(size 0 0)
			(layers "F.Cu" "F.Mask" "F.Paste")
			(net "FM_BIOS_USB_RECOVERY_R")
		)
		(pad "2" smd circle
			(at 0.40005 0 90)
			(size 0 0)
			(layers "F.Cu" "F.Mask" "F.Paste")
			(net "FM_BIOS_USB_RECOVERY")
		)
	)
	(footprint ""
		(layer "F.Cu")
		(at 63.861696 -164.276786 90)
		(property "Reference" "PC133"
			(at 0 0 90)
			(layer "F.SilkS")
			(hide yes)
			(effects
				(font
					(size 1.27 1.27)
				)
			)
		)
		(property "Value" ""
			(at 0 0 90)
			(layer "F.Fab")
			(effects
				(font
					(size 1.27 1.27)
				)
			)
		)
		(duplicate_pad_numbers_are_jumpers no)
		(fp_line
			(start 0.7874 -0.4064)
			(end 0.7874 0.4064)
			(stroke
				(width 0.1524)
				(type default)
			)
			(layer "F.SilkS")
		)
		(fp_line
			(start -0.7874 -0.4064)
			(end 0.7874 -0.4064)
			(stroke
				(width 0.1524)
				(type default)
			)
			(layer "F.SilkS")
		)
		(fp_line
			(start 0.7874 0.4064)
			(end -0.7874 0.4064)
			(stroke
				(width 0.1524)
				(type default)
			)
			(layer "F.SilkS")
		)
		(fp_line
			(start -0.7874 0.4064)
			(end -0.7874 -0.4064)
			(stroke
				(width 0.1524)
				(type default)
			)
			(layer "F.SilkS")
		)
		(fp_line
			(start -0.12065 -0.305054)
			(end -0.12065 -0.2794)
			(stroke
				(width 0.1)
				(type default)
			)
			(layer "F.Fab")
		)
		(fp_line
			(start -0.67945 -0.305054)
			(end -0.12065 -0.305054)
			(stroke
				(width 0.1)
				(type default)
			)
			(layer "F.Fab")
		)
		(fp_line
			(start 0.67945 -0.3048)
			(end 0.67945 0.3048)
			(stroke
				(width 0.1)
				(type default)
			)
			(layer "F.Fab")
		)
		(fp_line
			(start 0.12065 -0.3048)
			(end 0.67945 -0.3048)
			(stroke
				(width 0.1)
				(type default)
			)
			(layer "F.Fab")
		)
		(fp_line
			(start 0.12065 -0.2794)
			(end 0.12065 -0.3048)
			(stroke
				(width 0.1)
				(type default)
			)
			(layer "F.Fab")
		)
		(fp_line
			(start -0.12065 -0.2794)
			(end 0.12065 -0.2794)
			(stroke
				(width 0.1)
				(type default)
			)
			(layer "F.Fab")
		)
		(fp_line
			(start 0.120396 0.2794)
			(end -0.12065 0.2794)
			(stroke
				(width 0.1)
				(type default)
			)
			(layer "F.Fab")
		)
		(fp_line
			(start -0.12065 0.2794)
			(end -0.12065 0.3048)
			(stroke
				(width 0.1)
				(type default)
			)
			(layer "F.Fab")
		)
		(fp_line
			(start 0.67945 0.3048)
			(end 0.120396 0.3048)
			(stroke
				(width 0.1)
				(type default)
			)
			(layer "F.Fab")
		)
		(fp_line
			(start 0.120396 0.3048)
			(end 0.120396 0.2794)
			(stroke
				(width 0.1)
				(type default)
			)
			(layer "F.Fab")
		)
		(fp_line
			(start -0.12065 0.3048)
			(end -0.67945 0.3048)
			(stroke
				(width 0.1)
				(type default)
			)
			(layer "F.Fab")
		)
		(fp_line
			(start -0.67945 0.3048)
			(end -0.67945 -0.305054)
			(stroke
				(width 0.1)
				(type default)
			)
			(layer "F.Fab")
		)
		(pad "1" smd circle
			(at -0.40005 0 90)
			(size 0 0)
			(layers "F.Cu" "F.Mask" "F.Paste")
			(net "SW_PVDDCR_CPU0_P1_BOOT6_RC")
		)
		(pad "2" smd circle
			(at 0.40005 0 90)
			(size 0 0)
			(layers "F.Cu" "F.Mask" "F.Paste")
			(net "SW_PVDDCR_CPU0_P1_PH6")
		)
	)
)
